(kicad_pcb
	(version 20260206)
	(generator "pcbnew")
	(generator_version "10.0")
	(general
		(thickness 1.6)
		(legacy_teardrops no)
	)
	(paper "A4")
	(title_block
		(title "01162023_DA0F0TEBIF0_F0T_Expander_BD_F_brd_V02_OCP.brd")
		(comment 1 "Grand Teton / footprints 6410-6416 of 9728")
	)
	(layers
		(0 "F.Cu" signal "TOP")
		(4 "In1.Cu" signal "GND")
		(6 "In2.Cu" signal "VCC")
		(8 "In3.Cu" signal "VCC1")
		(10 "In4.Cu" signal "GND1")
		(12 "In5.Cu" signal "IN1")
		(14 "In6.Cu" signal "GND2")
		(16 "In7.Cu" signal "IN2")
		(18 "In8.Cu" signal "GND3")
		(20 "In9.Cu" signal "IN3")
		(22 "In10.Cu" signal "GND4")
		(24 "In11.Cu" signal "IN4")
		(26 "In12.Cu" signal "GND5")
		(28 "In13.Cu" signal "IN5")
		(30 "In14.Cu" signal "GND6")
		(32 "In15.Cu" signal "IN6")
		(34 "In16.Cu" signal "GND7")
		(2 "B.Cu" signal "BOTTOM")
		(9 "F.Adhes" user "F.Adhesive")
		(11 "B.Adhes" user "B.Adhesive")
		(13 "F.Paste" user "Package Geometry/Pastemask Top")
		(15 "B.Paste" user "Package Geometry/Pastemask Bottom")
		(5 "F.SilkS" user "Ref Des/Silkscreen Top")
		(7 "B.SilkS" user "Ref Des/Silkscreen Bottom")
		(1 "F.Mask" user "Board Geometry/Soldermask Top")
		(3 "B.Mask" user "Board Geometry/Soldermask Bottom")
		(17 "Dwgs.User" user "User.Drawings")
		(19 "Cmts.User" user "User.Comments")
		(21 "Eco1.User" user "User.Eco1")
		(23 "Eco2.User" user "User.Eco2")
		(25 "Edge.Cuts" user "Board Geometry/Outline")
		(27 "Margin" user)
		(31 "F.CrtYd" user "Package Geometry/Place Bound Top")
		(29 "B.CrtYd" user "Package Geometry/Place Bound Bottom")
		(35 "F.Fab" user "Ref Des/Assembly Top")
		(33 "B.Fab" user "Ref Des/Assembly Bottom")
	)
	(footprint ""
		(layer "F.Cu")
		(at 244.811042 -257.99796 -90)
		(property "Reference" "R6530"
			(at 0 0 270)
			(layer "F.SilkS")
			(hide yes)
			(effects
				(font
					(size 1.27 1.27)
				)
			)
		)
		(property "Value" ""
			(at 0 0 270)
			(layer "F.Fab")
			(effects
				(font
					(size 1.27 1.27)
				)
			)
		)
		(duplicate_pad_numbers_are_jumpers no)
		(fp_line
			(start -0.7874 0.4064)
			(end -0.7874 -0.4064)
			(stroke
				(width 0.1524)
				(type default)
			)
			(layer "F.SilkS")
		)
		(fp_line
			(start 0.7874 0.4064)
			(end -0.7874 0.4064)
			(stroke
				(width 0.1524)
				(type default)
			)
			(layer "F.SilkS")
		)
		(fp_line
			(start -0.7874 -0.4064)
			(end 0.7874 -0.4064)
			(stroke
				(width 0.1524)
				(type default)
			)
			(layer "F.SilkS")
		)
		(fp_line
			(start 0.7874 -0.4064)
			(end 0.7874 0.4064)
			(stroke
				(width 0.1524)
				(type default)
			)
			(layer "F.SilkS")
		)
		(fp_line
			(start -0.67945 0.3048)
			(end -0.67945 -0.305054)
			(stroke
				(width 0.1)
				(type default)
			)
			(layer "F.Fab")
		)
		(fp_line
			(start -0.12065 0.3048)
			(end -0.67945 0.3048)
			(stroke
				(width 0.1)
				(type default)
			)
			(layer "F.Fab")
		)
		(fp_line
			(start 0.120396 0.3048)
			(end 0.120396 0.2794)
			(stroke
				(width 0.1)
				(type default)
			)
			(layer "F.Fab")
		)
		(fp_line
			(start 0.67945 0.3048)
			(end 0.120396 0.3048)
			(stroke
				(width 0.1)
				(type default)
			)
			(layer "F.Fab")
		)
		(fp_line
			(start -0.12065 0.2794)
			(end -0.12065 0.3048)
			(stroke
				(width 0.1)
				(type default)
			)
			(layer "F.Fab")
		)
		(fp_line
			(start 0.120396 0.2794)
			(end -0.12065 0.2794)
			(stroke
				(width 0.1)
				(type default)
			)
			(layer "F.Fab")
		)
		(fp_line
			(start -0.12065 -0.2794)
			(end 0.12065 -0.2794)
			(stroke
				(width 0.1)
				(type default)
			)
			(layer "F.Fab")
		)
		(fp_line
			(start 0.12065 -0.2794)
			(end 0.12065 -0.3048)
			(stroke
				(width 0.1)
				(type default)
			)
			(layer "F.Fab")
		)
		(fp_line
			(start 0.12065 -0.3048)
			(end 0.67945 -0.3048)
			(stroke
				(width 0.1)
				(type default)
			)
			(layer "F.Fab")
		)
		(fp_line
			(start 0.67945 -0.3048)
			(end 0.67945 0.3048)
			(stroke
				(width 0.1)
				(type default)
			)
			(layer "F.Fab")
		)
		(fp_line
			(start -0.67945 -0.305054)
			(end -0.12065 -0.305054)
			(stroke
				(width 0.1)
				(type default)
			)
			(layer "F.Fab")
		)
		(fp_line
			(start -0.12065 -0.305054)
			(end -0.12065 -0.2794)
			(stroke
				(width 0.1)
				(type default)
			)
			(layer "F.Fab")
		)
		(pad "1" smd circle
			(at -0.40005 0 270)
			(size 0 0)
			(layers "F.Cu" "F.Mask" "F.Paste")
			(net "P1V25_SERDES_VDDPLL_PEX2")
		)
		(pad "2" smd circle
			(at 0.40005 0 270)
			(size 0 0)
			(layers "F.Cu" "F.Mask" "F.Paste")
			(net "P1V25_SERDES_VDDPLL_PEX2_C7")
		)
	)
	(footprint ""
		(layer "F.Cu")
		(at 393.022582 -44.341542 90)
		(property "Reference" "R657"
			(at 0 0 90)
			(layer "F.SilkS")
			(hide yes)
			(effects
				(font
					(size 1.27 1.27)
				)
			)
		)
		(property "Value" ""
			(at 0 0 90)
			(layer "F.Fab")
			(effects
				(font
					(size 1.27 1.27)
				)
			)
		)
		(duplicate_pad_numbers_are_jumpers no)
		(fp_line
			(start 0.7874 -0.4064)
			(end 0.7874 0.4064)
			(stroke
				(width 0.1524)
				(type default)
			)
			(layer "F.SilkS")
		)
		(fp_line
			(start -0.7874 -0.4064)
			(end 0.7874 -0.4064)
			(stroke
				(width 0.1524)
				(type default)
			)
			(layer "F.SilkS")
		)
		(fp_line
			(start 0.7874 0.4064)
			(end -0.7874 0.4064)
			(stroke
				(width 0.1524)
				(type default)
			)
			(layer "F.SilkS")
		)
		(fp_line
			(start -0.7874 0.4064)
			(end -0.7874 -0.4064)
			(stroke
				(width 0.1524)
				(type default)
			)
			(layer "F.SilkS")
		)
		(fp_line
			(start -0.12065 -0.305054)
			(end -0.12065 -0.2794)
			(stroke
				(width 0.1)
				(type default)
			)
			(layer "F.Fab")
		)
		(fp_line
			(start -0.67945 -0.305054)
			(end -0.12065 -0.305054)
			(stroke
				(width 0.1)
				(type default)
			)
			(layer "F.Fab")
		)
		(fp_line
			(start 0.67945 -0.3048)
			(end 0.67945 0.3048)
			(stroke
				(width 0.1)
				(type default)
			)
			(layer "F.Fab")
		)
		(fp_line
			(start 0.12065 -0.3048)
			(end 0.67945 -0.3048)
			(stroke
				(width 0.1)
				(type default)
			)
			(layer "F.Fab")
		)
		(fp_line
			(start 0.12065 -0.2794)
			(end 0.12065 -0.3048)
			(stroke
				(width 0.1)
				(type default)
			)
			(layer "F.Fab")
		)
		(fp_line
			(start -0.12065 -0.2794)
			(end 0.12065 -0.2794)
			(stroke
				(width 0.1)
				(type default)
			)
			(layer "F.Fab")
		)
		(fp_line
			(start 0.120396 0.2794)
			(end -0.12065 0.2794)
			(stroke
				(width 0.1)
				(type default)
			)
			(layer "F.Fab")
		)
		(fp_line
			(start -0.12065 0.2794)
			(end -0.12065 0.3048)
			(stroke
				(width 0.1)
				(type default)
			)
			(layer "F.Fab")
		)
		(fp_line
			(start 0.67945 0.3048)
			(end 0.120396 0.3048)
			(stroke
				(width 0.1)
				(type default)
			)
			(layer "F.Fab")
		)
		(fp_line
			(start 0.120396 0.3048)
			(end 0.120396 0.2794)
			(stroke
				(width 0.1)
				(type default)
			)
			(layer "F.Fab")
		)
		(fp_line
			(start -0.12065 0.3048)
			(end -0.67945 0.3048)
			(stroke
				(width 0.1)
				(type default)
			)
			(layer "F.Fab")
		)
		(fp_line
			(start -0.67945 0.3048)
			(end -0.67945 -0.305054)
			(stroke
				(width 0.1)
				(type default)
			)
			(layer "F.Fab")
		)
		(pad "1" smd circle
			(at -0.40005 0 90)
			(size 0 0)
			(layers "F.Cu" "F.Mask" "F.Paste")
			(net "P12V_SSD13")
		)
		(pad "2" smd circle
			(at 0.40005 0 90)
			(size 0 0)
			(layers "F.Cu" "F.Mask" "F.Paste")
			(net "P12V_SSD13_VIN_N")
		)
	)
	(footprint ""
		(layer "F.Cu")
		(at 424.573954 -26.31186 -90)
		(property "Reference" "U406"
			(at 0.20066 -2.401316 90)
			(unlocked yes)
			(layer "F.SilkS")
			(effects
				(font
					(size 0.7874 0.5842)
					(thickness 0.1524)
				)
			)
		)
		(property "Value" ""
			(at 0 0 270)
			(layer "F.Fab")
			(effects
				(font
					(size 1.27 1.27)
				)
			)
		)
		(duplicate_pad_numbers_are_jumpers no)
		(fp_line
			(start -1.949958 1.610106)
			(end -1.949958 -1.610106)
			(stroke
				(width 0.1524)
				(type default)
			)
			(layer "F.SilkS")
		)
		(fp_line
			(start 1.949958 1.610106)
			(end -1.949958 1.610106)
			(stroke
				(width 0.1524)
				(type default)
			)
			(layer "F.SilkS")
		)
		(fp_line
			(start 1.949958 -1.560068)
			(end 1.949958 1.610106)
			(stroke
				(width 0.1524)
				(type default)
			)
			(layer "F.SilkS")
		)
		(fp_line
			(start -1.949958 -1.610106)
			(end 1.949958 -1.610106)
			(stroke
				(width 0.1524)
				(type default)
			)
			(layer "F.SilkS")
		)
		(fp_line
			(start -0.750062 1.560068)
			(end -0.750062 -1.560068)
			(stroke
				(width 0.1)
				(type default)
			)
			(layer "F.Fab")
		)
		(fp_line
			(start 0.750062 1.560068)
			(end -0.750062 1.560068)
			(stroke
				(width 0.1)
				(type default)
			)
			(layer "F.Fab")
		)
		(fp_line
			(start -0.750062 -1.560068)
			(end 0.750062 -1.560068)
			(stroke
				(width 0.1)
				(type default)
			)
			(layer "F.Fab")
		)
		(fp_line
			(start 0.750062 -1.560068)
			(end 0.750062 1.560068)
			(stroke
				(width 0.1)
				(type default)
			)
			(layer "F.Fab")
		)
		(pad "D" smd rect
			(at 1.100074 0 180)
			(size 1.016 1.4224)
			(layers "F.Cu" "F.Mask" "F.Paste")
			(net "SSD14_LED_ISO_N")
		)
		(pad "G" smd rect
			(at -1.100074 -0.94996 180)
			(size 1.016 1.4224)
			(layers "F.Cu" "F.Mask" "F.Paste")
			(net "SSD14_LED_R")
		)
		(pad "S" smd rect
			(at -1.100074 0.94996 180)
			(size 1.016 1.4224)
			(layers "F.Cu" "F.Mask" "F.Paste")
			(net "GND")
		)
	)
	(footprint ""
		(layer "F.Cu")
		(at 355.913436 -138.360404 180)
		(property "Reference" "R4451"
			(at 0 0 180)
			(layer "F.SilkS")
			(hide yes)
			(effects
				(font
					(size 1.27 1.27)
				)
			)
		)
		(property "Value" ""
			(at 0 0 180)
			(layer "F.Fab")
			(effects
				(font
					(size 1.27 1.27)
				)
			)
		)
		(duplicate_pad_numbers_are_jumpers no)
		(fp_line
			(start 0.7874 0.4064)
			(end -0.7874 0.4064)
			(stroke
				(width 0.1524)
				(type default)
			)
			(layer "F.SilkS")
		)
		(fp_line
			(start 0.7874 -0.4064)
			(end 0.7874 0.4064)
			(stroke
				(width 0.1524)
				(type default)
			)
			(layer "F.SilkS")
		)
		(fp_line
			(start -0.7874 0.4064)
			(end -0.7874 -0.4064)
			(stroke
				(width 0.1524)
				(type default)
			)
			(layer "F.SilkS")
		)
		(fp_line
			(start -0.7874 -0.4064)
			(end 0.7874 -0.4064)
			(stroke
				(width 0.1524)
				(type default)
			)
			(layer "F.SilkS")
		)
		(fp_line
			(start 0.67945 0.3048)
			(end 0.120396 0.3048)
			(stroke
				(width 0.1)
				(type default)
			)
			(layer "F.Fab")
		)
		(fp_line
			(start 0.67945 -0.3048)
			(end 0.67945 0.3048)
			(stroke
				(width 0.1)
				(type default)
			)
			(layer "F.Fab")
		)
		(fp_line
			(start 0.12065 -0.2794)
			(end 0.12065 -0.3048)
			(stroke
				(width 0.1)
				(type default)
			)
			(layer "F.Fab")
		)
		(fp_line
			(start 0.12065 -0.3048)
			(end 0.67945 -0.3048)
			(stroke
				(width 0.1)
				(type default)
			)
			(layer "F.Fab")
		)
		(fp_line
			(start 0.120396 0.3048)
			(end 0.120396 0.2794)
			(stroke
				(width 0.1)
				(type default)
			)
			(layer "F.Fab")
		)
		(fp_line
			(start 0.120396 0.2794)
			(end -0.12065 0.2794)
			(stroke
				(width 0.1)
				(type default)
			)
			(layer "F.Fab")
		)
		(fp_line
			(start -0.12065 0.3048)
			(end -0.67945 0.3048)
			(stroke
				(width 0.1)
				(type default)
			)
			(layer "F.Fab")
		)
		(fp_line
			(start -0.12065 0.2794)
			(end -0.12065 0.3048)
			(stroke
				(width 0.1)
				(type default)
			)
			(layer "F.Fab")
		)
		(fp_line
			(start -0.12065 -0.2794)
			(end 0.12065 -0.2794)
			(stroke
				(width 0.1)
				(type default)
			)
			(layer "F.Fab")
		)
		(fp_line
			(start -0.12065 -0.305054)
			(end -0.12065 -0.2794)
			(stroke
				(width 0.1)
				(type default)
			)
			(layer "F.Fab")
		)
		(fp_line
			(start -0.67945 0.3048)
			(end -0.67945 -0.305054)
			(stroke
				(width 0.1)
				(type default)
			)
			(layer "F.Fab")
		)
		(fp_line
			(start -0.67945 -0.305054)
			(end -0.12065 -0.305054)
			(stroke
				(width 0.1)
				(type default)
			)
			(layer "F.Fab")
		)
		(pad "1" smd circle
			(at -0.40005 0 180)
			(size 0 0)
			(layers "F.Cu" "F.Mask" "F.Paste")
			(net "PWRGD_P12V_NIC6")
		)
		(pad "2" smd circle
			(at 0.40005 0 180)
			(size 0 0)
			(layers "F.Cu" "F.Mask" "F.Paste")
			(net "PWRGD_P12V_NIC6_R")
		)
	)
	(footprint ""
		(layer "F.Cu")
		(at 372.574058 -26.31186 -90)
		(property "Reference" "U408"
			(at 0.09906 -2.331212 90)
			(unlocked yes)
			(layer "F.SilkS")
			(effects
				(font
					(size 0.7874 0.5842)
					(thickness 0.1524)
				)
			)
		)
		(property "Value" ""
			(at 0 0 270)
			(layer "F.Fab")
			(effects
				(font
					(size 1.27 1.27)
				)
			)
		)
		(duplicate_pad_numbers_are_jumpers no)
		(fp_line
			(start -1.949958 1.610106)
			(end -1.949958 -1.610106)
			(stroke
				(width 0.1524)
				(type default)
			)
			(layer "F.SilkS")
		)
		(fp_line
			(start 1.949958 1.610106)
			(end -1.949958 1.610106)
			(stroke
				(width 0.1524)
				(type default)
			)
			(layer "F.SilkS")
		)
		(fp_line
			(start 1.949958 -1.560068)
			(end 1.949958 1.610106)
			(stroke
				(width 0.1524)
				(type default)
			)
			(layer "F.SilkS")
		)
		(fp_line
			(start -1.949958 -1.610106)
			(end 1.949958 -1.610106)
			(stroke
				(width 0.1524)
				(type default)
			)
			(layer "F.SilkS")
		)
		(fp_line
			(start -0.750062 1.560068)
			(end -0.750062 -1.560068)
			(stroke
				(width 0.1)
				(type default)
			)
			(layer "F.Fab")
		)
		(fp_line
			(start 0.750062 1.560068)
			(end -0.750062 1.560068)
			(stroke
				(width 0.1)
				(type default)
			)
			(layer "F.Fab")
		)
		(fp_line
			(start -0.750062 -1.560068)
			(end 0.750062 -1.560068)
			(stroke
				(width 0.1)
				(type default)
			)
			(layer "F.Fab")
		)
		(fp_line
			(start 0.750062 -1.560068)
			(end 0.750062 1.560068)
			(stroke
				(width 0.1)
				(type default)
			)
			(layer "F.Fab")
		)
		(pad "D" smd rect
			(at 1.100074 0 180)
			(size 1.016 1.4224)
			(layers "F.Cu" "F.Mask" "F.Paste")
			(net "SSD12_LED_ISO_N")
		)
		(pad "G" smd rect
			(at -1.100074 -0.94996 180)
			(size 1.016 1.4224)
			(layers "F.Cu" "F.Mask" "F.Paste")
			(net "SSD12_LED_R")
		)
		(pad "S" smd rect
			(at -1.100074 0.94996 180)
			(size 1.016 1.4224)
			(layers "F.Cu" "F.Mask" "F.Paste")
			(net "GND")
		)
	)
	(footprint ""
		(layer "F.Cu")
		(at 261.622286 -252.356874 -90)
		(property "Reference" "R1359"
			(at 0 0 270)
			(layer "F.SilkS")
			(hide yes)
			(effects
				(font
					(size 1.27 1.27)
				)
			)
		)
		(property "Value" ""
			(at 0 0 270)
			(layer "F.Fab")
			(effects
				(font
					(size 1.27 1.27)
				)
			)
		)
		(duplicate_pad_numbers_are_jumpers no)
		(fp_line
			(start -0.7874 0.4064)
			(end -0.7874 -0.4064)
			(stroke
				(width 0.1524)
				(type default)
			)
			(layer "F.SilkS")
		)
		(fp_line
			(start 0.7874 0.4064)
			(end -0.7874 0.4064)
			(stroke
				(width 0.1524)
				(type default)
			)
			(layer "F.SilkS")
		)
		(fp_line
			(start -0.7874 -0.4064)
			(end 0.7874 -0.4064)
			(stroke
				(width 0.1524)
				(type default)
			)
			(layer "F.SilkS")
		)
		(fp_line
			(start 0.7874 -0.4064)
			(end 0.7874 0.4064)
			(stroke
				(width 0.1524)
				(type default)
			)
			(layer "F.SilkS")
		)
		(fp_line
			(start -0.67945 0.3048)
			(end -0.67945 -0.305054)
			(stroke
				(width 0.1)
				(type default)
			)
			(layer "F.Fab")
		)
		(fp_line
			(start -0.12065 0.3048)
			(end -0.67945 0.3048)
			(stroke
				(width 0.1)
				(type default)
			)
			(layer "F.Fab")
		)
		(fp_line
			(start 0.120396 0.3048)
			(end 0.120396 0.2794)
			(stroke
				(width 0.1)
				(type default)
			)
			(layer "F.Fab")
		)
		(fp_line
			(start 0.67945 0.3048)
			(end 0.120396 0.3048)
			(stroke
				(width 0.1)
				(type default)
			)
			(layer "F.Fab")
		)
		(fp_line
			(start -0.12065 0.2794)
			(end -0.12065 0.3048)
			(stroke
				(width 0.1)
				(type default)
			)
			(layer "F.Fab")
		)
		(fp_line
			(start 0.120396 0.2794)
			(end -0.12065 0.2794)
			(stroke
				(width 0.1)
				(type default)
			)
			(layer "F.Fab")
		)
		(fp_line
			(start -0.12065 -0.2794)
			(end 0.12065 -0.2794)
			(stroke
				(width 0.1)
				(type default)
			)
			(layer "F.Fab")
		)
		(fp_line
			(start 0.12065 -0.2794)
			(end 0.12065 -0.3048)
			(stroke
				(width 0.1)
				(type default)
			)
			(layer "F.Fab")
		)
		(fp_line
			(start 0.12065 -0.3048)
			(end 0.67945 -0.3048)
			(stroke
				(width 0.1)
				(type default)
			)
			(layer "F.Fab")
		)
		(fp_line
			(start 0.67945 -0.3048)
			(end 0.67945 0.3048)
			(stroke
				(width 0.1)
				(type default)
			)
			(layer "F.Fab")
		)
		(fp_line
			(start -0.67945 -0.305054)
			(end -0.12065 -0.305054)
			(stroke
				(width 0.1)
				(type default)
			)
			(layer "F.Fab")
		)
		(fp_line
			(start -0.12065 -0.305054)
			(end -0.12065 -0.2794)
			(stroke
				(width 0.1)
				(type default)
			)
			(layer "F.Fab")
		)
		(pad "1" smd circle
			(at -0.40005 0 270)
			(size 0 0)
			(layers "F.Cu" "F.Mask" "F.Paste")
			(net "GND")
		)
		(pad "2" smd circle
			(at 0.40005 0 270)
			(size 0 0)
			(layers "F.Cu" "F.Mask" "F.Paste")
			(net "PEX2_MODE_SEL3")
		)
	)
	(footprint ""
		(layer "F.Cu")
		(at 2.87528 -69.182234)
		(property "Reference" "R5874"
			(at 0 0 0)
			(layer "F.SilkS")
			(hide yes)
			(effects
				(font
					(size 1.27 1.27)
				)
			)
		)
		(property "Value" ""
			(at 0 0 0)
			(layer "F.Fab")
			(effects
				(font
					(size 1.27 1.27)
				)
			)
		)
		(duplicate_pad_numbers_are_jumpers no)
		(fp_line
			(start -0.7874 -0.4064)
			(end 0.7874 -0.4064)
			(stroke
				(width 0.1524)
				(type default)
			)
			(layer "F.SilkS")
		)
		(fp_line
			(start -0.7874 0.4064)
			(end -0.7874 -0.4064)
			(stroke
				(width 0.1524)
				(type default)
			)
			(layer "F.SilkS")
		)
		(fp_line
			(start 0.7874 -0.4064)
			(end 0.7874 0.4064)
			(stroke
				(width 0.1524)
				(type default)
			)
			(layer "F.SilkS")
		)
		(fp_line
			(start 0.7874 0.4064)
			(end -0.7874 0.4064)
			(stroke
				(width 0.1524)
				(type default)
			)
			(layer "F.SilkS")
		)
		(fp_line
			(start -0.67945 -0.305054)
			(end -0.12065 -0.305054)
			(stroke
				(width 0.1)
				(type default)
			)
			(layer "F.Fab")
		)
		(fp_line
			(start -0.67945 0.3048)
			(end -0.67945 -0.305054)
			(stroke
				(width 0.1)
				(type default)
			)
			(layer "F.Fab")
		)
		(fp_line
			(start -0.12065 -0.305054)
			(end -0.12065 -0.2794)
			(stroke
				(width 0.1)
				(type default)
			)
			(layer "F.Fab")
		)
		(fp_line
			(start -0.12065 -0.2794)
			(end 0.12065 -0.2794)
			(stroke
				(width 0.1)
				(type default)
			)
			(layer "F.Fab")
		)
		(fp_line
			(start -0.12065 0.2794)
			(end -0.12065 0.3048)
			(stroke
				(width 0.1)
				(type default)
			)
			(layer "F.Fab")
		)
		(fp_line
			(start -0.12065 0.3048)
			(end -0.67945 0.3048)
			(stroke
				(width 0.1)
				(type default)
			)
			(layer "F.Fab")
		)
		(fp_line
			(start 0.120396 0.2794)
			(end -0.12065 0.2794)
			(stroke
				(width 0.1)
				(type default)
			)
			(layer "F.Fab")
		)
		(fp_line
			(start 0.120396 0.3048)
			(end 0.120396 0.2794)
			(stroke
				(width 0.1)
				(type default)
			)
			(layer "F.Fab")
		)
		(fp_line
			(start 0.12065 -0.3048)
			(end 0.67945 -0.3048)
			(stroke
				(width 0.1)
				(type default)
			)
			(layer "F.Fab")
		)
		(fp_line
			(start 0.12065 -0.2794)
			(end 0.12065 -0.3048)
			(stroke
				(width 0.1)
				(type default)
			)
			(layer "F.Fab")
		)
		(fp_line
			(start 0.67945 -0.3048)
			(end 0.67945 0.3048)
			(stroke
				(width 0.1)
				(type default)
			)
			(layer "F.Fab")
		)
		(fp_line
			(start 0.67945 0.3048)
			(end 0.120396 0.3048)
			(stroke
				(width 0.1)
				(type default)
			)
			(layer "F.Fab")
		)
		(pad "1" smd circle
			(at -0.40005 0)
			(size 0 0)
			(layers "F.Cu" "F.Mask" "F.Paste")
			(net "P3V3_SSD0")
		)
		(pad "2" smd circle
			(at 0.40005 0)
			(size 0 0)
			(layers "F.Cu" "F.Mask" "F.Paste")
			(net "P3V3_SSD0_PG_G1")
		)
	)
)
